(kicad_pcb
	(version 20260206)
	(generator "pcbnew")
	(generator_version "10.0")
	(general
		(thickness 1.6)
		(legacy_teardrops no)
	)
	(paper "A4")
	(title_block
		(title "04192023_DAF0TMB3IC0_F0TG_MB_C_brd_V02_OCP.brd")
		(comment 1 "Grand Teton / footprints 3567-3574 of 8354")
	)
	(layers
		(0 "F.Cu" signal "TOP")
		(4 "In1.Cu" signal "GND")
		(6 "In2.Cu" signal "IN1")
		(8 "In3.Cu" signal "GND1")
		(10 "In4.Cu" signal "IN2")
		(12 "In5.Cu" signal "GND2")
		(14 "In6.Cu" signal "IN3")
		(16 "In7.Cu" signal "GND3")
		(18 "In8.Cu" signal "VCC")
		(20 "In9.Cu" signal "VCC1")
		(22 "In10.Cu" signal "GND4")
		(24 "In11.Cu" signal "IN4")
		(26 "In12.Cu" signal "GND5")
		(28 "In13.Cu" signal "IN5")
		(30 "In14.Cu" signal "GND6")
		(32 "In15.Cu" signal "IN6")
		(34 "In16.Cu" signal "GND7")
		(2 "B.Cu" signal "BOTTOM")
		(9 "F.Adhes" user "F.Adhesive")
		(11 "B.Adhes" user "B.Adhesive")
		(13 "F.Paste" user "Package Geometry/Pastemask Top")
		(15 "B.Paste" user "Package Geometry/Pastemask Bottom")
		(5 "F.SilkS" user "Ref Des/Silkscreen Top")
		(7 "B.SilkS" user "Ref Des/Silkscreen Bottom")
		(1 "F.Mask" user "Board Geometry/Soldermask Top")
		(3 "B.Mask" user "Board Geometry/Soldermask Bottom")
		(17 "Dwgs.User" user "User.Drawings")
		(19 "Cmts.User" user "User.Comments")
		(21 "Eco1.User" user "User.Eco1")
		(23 "Eco2.User" user "User.Eco2")
		(25 "Edge.Cuts" user "Board Geometry/Outline")
		(27 "Margin" user)
		(31 "F.CrtYd" user "Package Geometry/Place Bound Top")
		(29 "B.CrtYd" user "Package Geometry/Place Bound Bottom")
		(35 "F.Fab" user "Ref Des/Assembly Top")
		(33 "B.Fab" user "Ref Des/Assembly Bottom")
	)
	(footprint ""
		(layer "F.Cu")
		(at 393.092178 -182.745634 90)
		(property "Reference" "PC549_C0P0_4"
			(at 0 0 90)
			(layer "F.SilkS")
			(hide yes)
			(effects
				(font
					(size 1.27 1.27)
				)
			)
		)
		(property "Value" ""
			(at 0 0 90)
			(layer "F.Fab")
			(effects
				(font
					(size 1.27 1.27)
				)
			)
		)
		(duplicate_pad_numbers_are_jumpers no)
		(fp_line
			(start 0.7874 -0.4064)
			(end 0.7874 0.4064)
			(stroke
				(width 0.1524)
				(type default)
			)
			(layer "F.SilkS")
		)
		(fp_line
			(start -0.7874 -0.4064)
			(end 0.7874 -0.4064)
			(stroke
				(width 0.1524)
				(type default)
			)
			(layer "F.SilkS")
		)
		(fp_line
			(start 0.7874 0.4064)
			(end -0.7874 0.4064)
			(stroke
				(width 0.1524)
				(type default)
			)
			(layer "F.SilkS")
		)
		(fp_line
			(start -0.7874 0.4064)
			(end -0.7874 -0.4064)
			(stroke
				(width 0.1524)
				(type default)
			)
			(layer "F.SilkS")
		)
		(fp_line
			(start -0.12065 -0.305054)
			(end -0.12065 -0.2794)
			(stroke
				(width 0.1)
				(type default)
			)
			(layer "F.Fab")
		)
		(fp_line
			(start -0.67945 -0.305054)
			(end -0.12065 -0.305054)
			(stroke
				(width 0.1)
				(type default)
			)
			(layer "F.Fab")
		)
		(fp_line
			(start 0.67945 -0.3048)
			(end 0.67945 0.3048)
			(stroke
				(width 0.1)
				(type default)
			)
			(layer "F.Fab")
		)
		(fp_line
			(start 0.12065 -0.3048)
			(end 0.67945 -0.3048)
			(stroke
				(width 0.1)
				(type default)
			)
			(layer "F.Fab")
		)
		(fp_line
			(start 0.12065 -0.2794)
			(end 0.12065 -0.3048)
			(stroke
				(width 0.1)
				(type default)
			)
			(layer "F.Fab")
		)
		(fp_line
			(start -0.12065 -0.2794)
			(end 0.12065 -0.2794)
			(stroke
				(width 0.1)
				(type default)
			)
			(layer "F.Fab")
		)
		(fp_line
			(start 0.120396 0.2794)
			(end -0.12065 0.2794)
			(stroke
				(width 0.1)
				(type default)
			)
			(layer "F.Fab")
		)
		(fp_line
			(start -0.12065 0.2794)
			(end -0.12065 0.3048)
			(stroke
				(width 0.1)
				(type default)
			)
			(layer "F.Fab")
		)
		(fp_line
			(start 0.67945 0.3048)
			(end 0.120396 0.3048)
			(stroke
				(width 0.1)
				(type default)
			)
			(layer "F.Fab")
		)
		(fp_line
			(start 0.120396 0.3048)
			(end 0.120396 0.2794)
			(stroke
				(width 0.1)
				(type default)
			)
			(layer "F.Fab")
		)
		(fp_line
			(start -0.12065 0.3048)
			(end -0.67945 0.3048)
			(stroke
				(width 0.1)
				(type default)
			)
			(layer "F.Fab")
		)
		(fp_line
			(start -0.67945 0.3048)
			(end -0.67945 -0.305054)
			(stroke
				(width 0.1)
				(type default)
			)
			(layer "F.Fab")
		)
		(pad "1" smd circle
			(at -0.40005 0 90)
			(size 0 0)
			(layers "F.Cu" "F.Mask" "F.Paste")
			(net "PVDDCR_CPU0_P0_PVCC")
		)
		(pad "2" smd circle
			(at 0.40005 0 90)
			(size 0 0)
			(layers "F.Cu" "F.Mask" "F.Paste")
			(net "GND")
		)
	)
	(footprint ""
		(layer "F.Cu")
		(at 419.95344 -381.41783 -90)
		(property "Reference" "C846"
			(at 0 0 270)
			(layer "F.SilkS")
			(hide yes)
			(effects
				(font
					(size 1.27 1.27)
				)
			)
		)
		(property "Value" ""
			(at 0 0 270)
			(layer "F.Fab")
			(effects
				(font
					(size 1.27 1.27)
				)
			)
		)
		(duplicate_pad_numbers_are_jumpers no)
		(fp_line
			(start -0.299974 0.150114)
			(end -0.299974 -0.150114)
			(stroke
				(width 0.1)
				(type default)
			)
			(layer "F.Fab")
		)
		(fp_line
			(start 0.299974 0.150114)
			(end -0.299974 0.150114)
			(stroke
				(width 0.1)
				(type default)
			)
			(layer "F.Fab")
		)
		(fp_line
			(start -0.299974 -0.150114)
			(end 0.299974 -0.150114)
			(stroke
				(width 0.1)
				(type default)
			)
			(layer "F.Fab")
		)
		(fp_line
			(start 0.299974 -0.150114)
			(end 0.299974 0.150114)
			(stroke
				(width 0.1)
				(type default)
			)
			(layer "F.Fab")
		)
		(pad "1" smd rect
			(at -0.2667 0 270)
			(size 0.3048 0.381)
			(layers "F.Cu" "F.Mask" "F.Paste")
			(net "P5E_CPU0_P2_TX_C_DN<11>")
		)
		(pad "2" smd rect
			(at 0.2667 0 270)
			(size 0.3048 0.381)
			(layers "F.Cu" "F.Mask" "F.Paste")
			(net "P5E_CPU0_P2_TX_DN<11>")
		)
	)
	(footprint ""
		(layer "F.Cu")
		(at 322.603876 -70.098412 90)
		(property "Reference" "D73"
			(at -3.934714 -0.691642 90)
			(unlocked yes)
			(layer "F.SilkS")
			(effects
				(font
					(size 0.7874 0.5842)
					(thickness 0.1524)
				)
				(justify left)
			)
		)
		(property "Value" ""
			(at 0 0 90)
			(layer "F.Fab")
			(effects
				(font
					(size 1.27 1.27)
				)
			)
		)
		(duplicate_pad_numbers_are_jumpers no)
		(fp_line
			(start 1.16078 -0.4826)
			(end 1.16078 0.4826)
			(stroke
				(width 0.1524)
				(type default)
			)
			(layer "F.SilkS")
		)
		(fp_line
			(start 1.03378 -0.4826)
			(end 1.03378 0.4826)
			(stroke
				(width 0.1524)
				(type default)
			)
			(layer "F.SilkS")
		)
		(fp_line
			(start 0.90678 -0.4826)
			(end 0.90678 0.4826)
			(stroke
				(width 0.1524)
				(type default)
			)
			(layer "F.SilkS")
		)
		(fp_line
			(start -0.64008 -0.4826)
			(end 1.16078 -0.4826)
			(stroke
				(width 0.1524)
				(type default)
			)
			(layer "F.SilkS")
		)
		(fp_line
			(start -0.79248 -0.4826)
			(end 1.03378 -0.4826)
			(stroke
				(width 0.1524)
				(type default)
			)
			(layer "F.SilkS")
		)
		(fp_line
			(start -0.89408 -0.4826)
			(end 0.90678 -0.4826)
			(stroke
				(width 0.1524)
				(type default)
			)
			(layer "F.SilkS")
		)
		(fp_line
			(start 1.16078 0.4826)
			(end -0.64008 0.4826)
			(stroke
				(width 0.1524)
				(type default)
			)
			(layer "F.SilkS")
		)
		(fp_line
			(start 1.03378 0.4826)
			(end -0.79248 0.4826)
			(stroke
				(width 0.1524)
				(type default)
			)
			(layer "F.SilkS")
		)
		(fp_line
			(start 0.90678 0.4826)
			(end -0.90678 0.4826)
			(stroke
				(width 0.1524)
				(type default)
			)
			(layer "F.SilkS")
		)
		(fp_line
			(start -0.90678 0.4826)
			(end -0.90678 -0.4699)
			(stroke
				(width 0.1524)
				(type default)
			)
			(layer "F.SilkS")
		)
		(fp_line
			(start 0.499872 -0.249936)
			(end 0.499872 0.249936)
			(stroke
				(width 0.1)
				(type default)
			)
			(layer "F.Fab")
		)
		(fp_line
			(start -0.499872 -0.249936)
			(end 0.499872 -0.249936)
			(stroke
				(width 0.1)
				(type default)
			)
			(layer "F.Fab")
		)
		(fp_line
			(start 0.499872 0.249936)
			(end -0.499872 0.249936)
			(stroke
				(width 0.1)
				(type default)
			)
			(layer "F.Fab")
		)
		(fp_line
			(start -0.499872 0.249936)
			(end -0.499872 -0.249936)
			(stroke
				(width 0.1)
				(type default)
			)
			(layer "F.Fab")
		)
		(pad "A" smd rect
			(at -0.47498 0 90)
			(size 0.6096 0.7112)
			(layers "F.Cu" "F.Mask" "F.Paste")
			(net "LED_PWRGD_PVDD33_S5_R")
		)
		(pad "C" smd rect
			(at 0.47498 0 90)
			(size 0.6096 0.7112)
			(layers "F.Cu" "F.Mask" "F.Paste")
			(net "LED_PWRGD_PVDD33_S5_D")
		)
	)
	(footprint ""
		(layer "F.Cu")
		(at 436.526432 -26.056336 90)
		(property "Reference" "PR3840"
			(at 0 0 90)
			(layer "F.SilkS")
			(hide yes)
			(effects
				(font
					(size 1.27 1.27)
				)
			)
		)
		(property "Value" ""
			(at 0 0 90)
			(layer "F.Fab")
			(effects
				(font
					(size 1.27 1.27)
				)
			)
		)
		(duplicate_pad_numbers_are_jumpers no)
		(fp_line
			(start 0.7874 -0.4064)
			(end 0.7874 0.4064)
			(stroke
				(width 0.1524)
				(type default)
			)
			(layer "F.SilkS")
		)
		(fp_line
			(start -0.7874 -0.4064)
			(end 0.7874 -0.4064)
			(stroke
				(width 0.1524)
				(type default)
			)
			(layer "F.SilkS")
		)
		(fp_line
			(start 0.7874 0.4064)
			(end -0.7874 0.4064)
			(stroke
				(width 0.1524)
				(type default)
			)
			(layer "F.SilkS")
		)
		(fp_line
			(start -0.7874 0.4064)
			(end -0.7874 -0.4064)
			(stroke
				(width 0.1524)
				(type default)
			)
			(layer "F.SilkS")
		)
		(fp_line
			(start -0.12065 -0.305054)
			(end -0.12065 -0.2794)
			(stroke
				(width 0.1)
				(type default)
			)
			(layer "F.Fab")
		)
		(fp_line
			(start -0.67945 -0.305054)
			(end -0.12065 -0.305054)
			(stroke
				(width 0.1)
				(type default)
			)
			(layer "F.Fab")
		)
		(fp_line
			(start 0.67945 -0.3048)
			(end 0.67945 0.3048)
			(stroke
				(width 0.1)
				(type default)
			)
			(layer "F.Fab")
		)
		(fp_line
			(start 0.12065 -0.3048)
			(end 0.67945 -0.3048)
			(stroke
				(width 0.1)
				(type default)
			)
			(layer "F.Fab")
		)
		(fp_line
			(start 0.12065 -0.2794)
			(end 0.12065 -0.3048)
			(stroke
				(width 0.1)
				(type default)
			)
			(layer "F.Fab")
		)
		(fp_line
			(start -0.12065 -0.2794)
			(end 0.12065 -0.2794)
			(stroke
				(width 0.1)
				(type default)
			)
			(layer "F.Fab")
		)
		(fp_line
			(start 0.120396 0.2794)
			(end -0.12065 0.2794)
			(stroke
				(width 0.1)
				(type default)
			)
			(layer "F.Fab")
		)
		(fp_line
			(start -0.12065 0.2794)
			(end -0.12065 0.3048)
			(stroke
				(width 0.1)
				(type default)
			)
			(layer "F.Fab")
		)
		(fp_line
			(start 0.67945 0.3048)
			(end 0.120396 0.3048)
			(stroke
				(width 0.1)
				(type default)
			)
			(layer "F.Fab")
		)
		(fp_line
			(start 0.120396 0.3048)
			(end 0.120396 0.2794)
			(stroke
				(width 0.1)
				(type default)
			)
			(layer "F.Fab")
		)
		(fp_line
			(start -0.12065 0.3048)
			(end -0.67945 0.3048)
			(stroke
				(width 0.1)
				(type default)
			)
			(layer "F.Fab")
		)
		(fp_line
			(start -0.67945 0.3048)
			(end -0.67945 -0.305054)
			(stroke
				(width 0.1)
				(type default)
			)
			(layer "F.Fab")
		)
		(pad "1" smd circle
			(at -0.40005 0 90)
			(size 0 0)
			(layers "F.Cu" "F.Mask" "F.Paste")
			(net "P12V_OCP_SFF")
		)
		(pad "2" smd circle
			(at 0.40005 0 90)
			(size 0 0)
			(layers "F.Cu" "F.Mask" "F.Paste")
			(net "P12V_OCP_OV_FB_1")
		)
	)
	(footprint ""
		(layer "F.Cu")
		(at 136.652 -113.157)
		(property "Reference" "C8019"
			(at 0 0 0)
			(layer "F.SilkS")
			(hide yes)
			(effects
				(font
					(size 1.27 1.27)
				)
			)
		)
		(property "Value" ""
			(at 0 0 0)
			(layer "F.Fab")
			(effects
				(font
					(size 1.27 1.27)
				)
			)
		)
		(duplicate_pad_numbers_are_jumpers no)
		(fp_line
			(start -0.7874 -0.4064)
			(end 0.7874 -0.4064)
			(stroke
				(width 0.1524)
				(type default)
			)
			(layer "F.SilkS")
		)
		(fp_line
			(start -0.7874 0.4064)
			(end -0.7874 -0.4064)
			(stroke
				(width 0.1524)
				(type default)
			)
			(layer "F.SilkS")
		)
		(fp_line
			(start 0.7874 -0.4064)
			(end 0.7874 0.4064)
			(stroke
				(width 0.1524)
				(type default)
			)
			(layer "F.SilkS")
		)
		(fp_line
			(start 0.7874 0.4064)
			(end -0.7874 0.4064)
			(stroke
				(width 0.1524)
				(type default)
			)
			(layer "F.SilkS")
		)
		(fp_line
			(start -0.67945 -0.305054)
			(end -0.12065 -0.305054)
			(stroke
				(width 0.1)
				(type default)
			)
			(layer "F.Fab")
		)
		(fp_line
			(start -0.67945 0.3048)
			(end -0.67945 -0.305054)
			(stroke
				(width 0.1)
				(type default)
			)
			(layer "F.Fab")
		)
		(fp_line
			(start -0.12065 -0.305054)
			(end -0.12065 -0.2794)
			(stroke
				(width 0.1)
				(type default)
			)
			(layer "F.Fab")
		)
		(fp_line
			(start -0.12065 -0.2794)
			(end 0.12065 -0.2794)
			(stroke
				(width 0.1)
				(type default)
			)
			(layer "F.Fab")
		)
		(fp_line
			(start -0.12065 0.2794)
			(end -0.12065 0.3048)
			(stroke
				(width 0.1)
				(type default)
			)
			(layer "F.Fab")
		)
		(fp_line
			(start -0.12065 0.3048)
			(end -0.67945 0.3048)
			(stroke
				(width 0.1)
				(type default)
			)
			(layer "F.Fab")
		)
		(fp_line
			(start 0.120396 0.2794)
			(end -0.12065 0.2794)
			(stroke
				(width 0.1)
				(type default)
			)
			(layer "F.Fab")
		)
		(fp_line
			(start 0.120396 0.3048)
			(end 0.120396 0.2794)
			(stroke
				(width 0.1)
				(type default)
			)
			(layer "F.Fab")
		)
		(fp_line
			(start 0.12065 -0.3048)
			(end 0.67945 -0.3048)
			(stroke
				(width 0.1)
				(type default)
			)
			(layer "F.Fab")
		)
		(fp_line
			(start 0.12065 -0.2794)
			(end 0.12065 -0.3048)
			(stroke
				(width 0.1)
				(type default)
			)
			(layer "F.Fab")
		)
		(fp_line
			(start 0.67945 -0.3048)
			(end 0.67945 0.3048)
			(stroke
				(width 0.1)
				(type default)
			)
			(layer "F.Fab")
		)
		(fp_line
			(start 0.67945 0.3048)
			(end 0.120396 0.3048)
			(stroke
				(width 0.1)
				(type default)
			)
			(layer "F.Fab")
		)
		(pad "1" smd circle
			(at -0.40005 0)
			(size 0 0)
			(layers "F.Cu" "F.Mask" "F.Paste")
			(net "P12V_AUX")
		)
		(pad "2" smd circle
			(at 0.40005 0)
			(size 0 0)
			(layers "F.Cu" "F.Mask" "F.Paste")
			(net "GND")
		)
	)
	(footprint ""
		(layer "F.Cu")
		(at 333.629 -160.909 90)
		(property "Reference" "PC115"
			(at -0.889 -3.52933 90)
			(unlocked yes)
			(layer "F.SilkS")
			(effects
				(font
					(size 0.7874 0.5842)
					(thickness 0.1524)
				)
				(justify left)
			)
		)
		(property "Value" ""
			(at 0 0 90)
			(layer "F.Fab")
			(effects
				(font
					(size 1.27 1.27)
				)
			)
		)
		(duplicate_pad_numbers_are_jumpers no)
		(fp_line
			(start 2.750058 -2.750058)
			(end -1.988058 -2.750058)
			(stroke
				(width 0.1524)
				(type default)
			)
			(layer "F.SilkS")
		)
		(fp_line
			(start -1.988058 -2.750058)
			(end -2.750058 -1.988058)
			(stroke
				(width 0.1524)
				(type default)
			)
			(layer "F.SilkS")
		)
		(fp_line
			(start -2.750058 -1.988058)
			(end -2.750058 -0.9398)
			(stroke
				(width 0.1524)
				(type default)
			)
			(layer "F.SilkS")
		)
		(fp_line
			(start 2.750058 -0.9398)
			(end 2.750058 -2.750058)
			(stroke
				(width 0.1524)
				(type default)
			)
			(layer "F.SilkS")
		)
		(fp_line
			(start -2.750058 0.9398)
			(end -2.750058 1.988058)
			(stroke
				(width 0.1524)
				(type default)
			)
			(layer "F.SilkS")
		)
		(fp_line
			(start -2.750058 1.988058)
			(end -1.988058 2.750058)
			(stroke
				(width 0.1524)
				(type default)
			)
			(layer "F.SilkS")
		)
		(fp_line
			(start 2.750058 2.750058)
			(end 2.750058 0.9398)
			(stroke
				(width 0.1524)
				(type default)
			)
			(layer "F.SilkS")
		)
		(fp_line
			(start -1.988058 2.750058)
			(end 2.750058 2.750058)
			(stroke
				(width 0.1524)
				(type default)
			)
			(layer "F.SilkS")
		)
		(fp_line
			(start 2.750058 -2.750058)
			(end -2.750058 -2.750058)
			(stroke
				(width 0.1)
				(type default)
			)
			(layer "F.Fab")
		)
		(fp_line
			(start -2.750058 -2.750058)
			(end -2.750058 2.750058)
			(stroke
				(width 0.1)
				(type default)
			)
			(layer "F.Fab")
		)
		(fp_line
			(start 2.750058 2.750058)
			(end 2.750058 -2.750058)
			(stroke
				(width 0.1)
				(type default)
			)
			(layer "F.Fab")
		)
		(fp_line
			(start -2.750058 2.750058)
			(end 2.750058 2.750058)
			(stroke
				(width 0.1)
				(type default)
			)
			(layer "F.Fab")
		)
		(pad "1" smd rect
			(at -2.199894 0 180)
			(size 1.6002 3.0226)
			(layers "F.Cu" "F.Mask" "F.Paste")
			(net "PVDD18_S5_P0")
		)
		(pad "2" smd rect
			(at 2.199894 0 180)
			(size 1.6002 3.0226)
			(layers "F.Cu" "F.Mask" "F.Paste")
			(net "GND")
		)
	)
	(footprint ""
		(layer "F.Cu")
		(at 63.15075 -193.594228)
		(property "Reference" "TP14"
			(at 0 0 0)
			(layer "F.SilkS")
			(hide yes)
			(effects
				(font
					(size 1.27 1.27)
				)
			)
		)
		(property "Value" ""
			(at 0 0 0)
			(layer "F.Fab")
			(effects
				(font
					(size 1.27 1.27)
				)
			)
		)
		(duplicate_pad_numbers_are_jumpers no)
		(pad "1" smd circle
			(at 0 0)
			(size 0.762 0.762)
			(layers "F.Cu" "F.Mask" "F.Paste")
			(net "VSENSE_PVDD18_S5_P1_DN")
		)
	)
	(footprint ""
		(layer "F.Cu")
		(at 303.861724 -406.133808)
		(property "Reference" "C556"
			(at 0 0 0)
			(layer "F.SilkS")
			(hide yes)
			(effects
				(font
					(size 1.27 1.27)
				)
			)
		)
		(property "Value" ""
			(at 0 0 0)
			(layer "F.Fab")
			(effects
				(font
					(size 1.27 1.27)
				)
			)
		)
		(duplicate_pad_numbers_are_jumpers no)
		(fp_line
			(start -1.524 -0.762)
			(end 1.524 -0.762)
			(stroke
				(width 0.1524)
				(type default)
			)
			(layer "F.SilkS")
		)
		(fp_line
			(start -1.524 0.762)
			(end -1.524 -0.762)
			(stroke
				(width 0.1524)
				(type default)
			)
			(layer "F.SilkS")
		)
		(fp_line
			(start 1.524 -0.762)
			(end 1.524 0.762)
			(stroke
				(width 0.1524)
				(type default)
			)
			(layer "F.SilkS")
		)
		(fp_line
			(start 1.524 0.762)
			(end -1.524 0.762)
			(stroke
				(width 0.1524)
				(type default)
			)
			(layer "F.SilkS")
		)
		(fp_line
			(start -1.1049 -0.724916)
			(end -1.1049 0.724916)
			(stroke
				(width 0.1)
				(type default)
			)
			(layer "F.Fab")
		)
		(fp_line
			(start -1.1049 0.724916)
			(end 1.1049 0.724916)
			(stroke
				(width 0.1)
				(type default)
			)
			(layer "F.Fab")
		)
		(fp_line
			(start 1.1049 -0.724916)
			(end -1.1049 -0.724916)
			(stroke
				(width 0.1)
				(type default)
			)
			(layer "F.Fab")
		)
		(fp_line
			(start 1.1049 0.724916)
			(end 1.1049 -0.724916)
			(stroke
				(width 0.1)
				(type default)
			)
			(layer "F.Fab")
		)
		(pad "1" smd rect
			(at -0.889 0 180)
			(size 1.016 1.27)
			(layers "F.Cu" "F.Mask" "F.Paste")
			(net "P0V9_CPU0_RT0_2A")
		)
		(pad "2" smd rect
			(at 0.889 0 180)
			(size 1.016 1.27)
			(layers "F.Cu" "F.Mask" "F.Paste")
			(net "GND")
		)
	)
)
